(kicad_pcb
	(version 20260206)
	(generator "pcbnew")
	(generator_version "10.0")
	(general
		(thickness 1.6)
		(legacy_teardrops no)
	)
	(paper "A4")
	(title_block
		(title "04192023_DAF0TMB3IC0_F0TG_MB_C_brd_V02_OCP.brd")
		(comment 1 "Grand Teton / footprints 5785-5791 of 8354")
	)
	(layers
		(0 "F.Cu" signal "TOP")
		(4 "In1.Cu" signal "GND")
		(6 "In2.Cu" signal "IN1")
		(8 "In3.Cu" signal "GND1")
		(10 "In4.Cu" signal "IN2")
		(12 "In5.Cu" signal "GND2")
		(14 "In6.Cu" signal "IN3")
		(16 "In7.Cu" signal "GND3")
		(18 "In8.Cu" signal "VCC")
		(20 "In9.Cu" signal "VCC1")
		(22 "In10.Cu" signal "GND4")
		(24 "In11.Cu" signal "IN4")
		(26 "In12.Cu" signal "GND5")
		(28 "In13.Cu" signal "IN5")
		(30 "In14.Cu" signal "GND6")
		(32 "In15.Cu" signal "IN6")
		(34 "In16.Cu" signal "GND7")
		(2 "B.Cu" signal "BOTTOM")
		(9 "F.Adhes" user "F.Adhesive")
		(11 "B.Adhes" user "B.Adhesive")
		(13 "F.Paste" user "Package Geometry/Pastemask Top")
		(15 "B.Paste" user "Package Geometry/Pastemask Bottom")
		(5 "F.SilkS" user "Ref Des/Silkscreen Top")
		(7 "B.SilkS" user "Ref Des/Silkscreen Bottom")
		(1 "F.Mask" user "Board Geometry/Soldermask Top")
		(3 "B.Mask" user "Board Geometry/Soldermask Bottom")
		(17 "Dwgs.User" user "User.Drawings")
		(19 "Cmts.User" user "User.Comments")
		(21 "Eco1.User" user "User.Eco1")
		(23 "Eco2.User" user "User.Eco2")
		(25 "Edge.Cuts" user "Board Geometry/Outline")
		(27 "Margin" user)
		(31 "F.CrtYd" user "Package Geometry/Place Bound Top")
		(29 "B.CrtYd" user "Package Geometry/Place Bound Bottom")
		(35 "F.Fab" user "Ref Des/Assembly Top")
		(33 "B.Fab" user "Ref Des/Assembly Bottom")
	)
	(footprint ""
		(layer "B.Cu")
		(at 68.547234 -201.545952 90)
		(property "Reference" "R556"
			(at 0 0 90)
			(layer "B.SilkS")
			(hide yes)
			(effects
				(font
					(size 1.27 1.27)
				)
				(justify mirror)
			)
		)
		(property "Value" ""
			(at 0 0 90)
			(layer "B.Fab")
			(effects
				(font
					(size 1.27 1.27)
				)
				(justify mirror)
			)
		)
		(duplicate_pad_numbers_are_jumpers no)
		(fp_line
			(start 0.7874 -0.4064)
			(end -0.7874 -0.4064)
			(stroke
				(width 0.1524)
				(type default)
			)
			(layer "B.SilkS")
		)
		(fp_line
			(start -0.7874 -0.4064)
			(end -0.7874 0.4064)
			(stroke
				(width 0.1524)
				(type default)
			)
			(layer "B.SilkS")
		)
		(fp_line
			(start 0.7874 0.4064)
			(end 0.7874 -0.4064)
			(stroke
				(width 0.1524)
				(type default)
			)
			(layer "B.SilkS")
		)
		(fp_line
			(start -0.7874 0.4064)
			(end 0.7874 0.4064)
			(stroke
				(width 0.1524)
				(type default)
			)
			(layer "B.SilkS")
		)
		(fp_line
			(start 0.67945 -0.305054)
			(end 0.12065 -0.305054)
			(stroke
				(width 0.1)
				(type default)
			)
			(layer "B.Fab")
		)
		(fp_line
			(start 0.12065 -0.305054)
			(end 0.12065 -0.2794)
			(stroke
				(width 0.1)
				(type default)
			)
			(layer "B.Fab")
		)
		(fp_line
			(start -0.12065 -0.3048)
			(end -0.67945 -0.3048)
			(stroke
				(width 0.1)
				(type default)
			)
			(layer "B.Fab")
		)
		(fp_line
			(start -0.67945 -0.3048)
			(end -0.67945 0.3048)
			(stroke
				(width 0.1)
				(type default)
			)
			(layer "B.Fab")
		)
		(fp_line
			(start 0.12065 -0.2794)
			(end -0.12065 -0.2794)
			(stroke
				(width 0.1)
				(type default)
			)
			(layer "B.Fab")
		)
		(fp_line
			(start -0.12065 -0.2794)
			(end -0.12065 -0.3048)
			(stroke
				(width 0.1)
				(type default)
			)
			(layer "B.Fab")
		)
		(fp_line
			(start 0.12065 0.2794)
			(end 0.12065 0.3048)
			(stroke
				(width 0.1)
				(type default)
			)
			(layer "B.Fab")
		)
		(fp_line
			(start -0.120396 0.2794)
			(end 0.12065 0.2794)
			(stroke
				(width 0.1)
				(type default)
			)
			(layer "B.Fab")
		)
		(fp_line
			(start 0.67945 0.3048)
			(end 0.67945 -0.305054)
			(stroke
				(width 0.1)
				(type default)
			)
			(layer "B.Fab")
		)
		(fp_line
			(start 0.12065 0.3048)
			(end 0.67945 0.3048)
			(stroke
				(width 0.1)
				(type default)
			)
			(layer "B.Fab")
		)
		(fp_line
			(start -0.120396 0.3048)
			(end -0.120396 0.2794)
			(stroke
				(width 0.1)
				(type default)
			)
			(layer "B.Fab")
		)
		(fp_line
			(start -0.67945 0.3048)
			(end -0.120396 0.3048)
			(stroke
				(width 0.1)
				(type default)
			)
			(layer "B.Fab")
		)
		(pad "1" smd circle
			(at 0.40005 0 270)
			(size 0 0)
			(layers "B.Cu" "B.Mask" "B.Paste")
			(net "PVDD18_S5_P1")
		)
		(pad "2" smd circle
			(at -0.40005 0 270)
			(size 0 0)
			(layers "B.Cu" "B.Mask" "B.Paste")
			(net "RST_CPU1_RESETL_N")
		)
	)
	(footprint ""
		(layer "B.Cu")
		(at 368.630962 -214.287608 180)
		(property "Reference" "PR303"
			(at 0 0 0)
			(layer "B.SilkS")
			(hide yes)
			(effects
				(font
					(size 1.27 1.27)
				)
				(justify mirror)
			)
		)
		(property "Value" ""
			(at 0 0 0)
			(layer "B.Fab")
			(effects
				(font
					(size 1.27 1.27)
				)
				(justify mirror)
			)
		)
		(duplicate_pad_numbers_are_jumpers no)
		(fp_line
			(start 0.7874 0.4064)
			(end 0.7874 -0.4064)
			(stroke
				(width 0.1524)
				(type default)
			)
			(layer "B.SilkS")
		)
		(fp_line
			(start 0.7874 -0.4064)
			(end -0.7874 -0.4064)
			(stroke
				(width 0.1524)
				(type default)
			)
			(layer "B.SilkS")
		)
		(fp_line
			(start -0.7874 0.4064)
			(end 0.7874 0.4064)
			(stroke
				(width 0.1524)
				(type default)
			)
			(layer "B.SilkS")
		)
		(fp_line
			(start -0.7874 -0.4064)
			(end -0.7874 0.4064)
			(stroke
				(width 0.1524)
				(type default)
			)
			(layer "B.SilkS")
		)
		(fp_line
			(start 0.67945 0.3048)
			(end 0.67945 -0.305054)
			(stroke
				(width 0.1)
				(type default)
			)
			(layer "B.Fab")
		)
		(fp_line
			(start 0.67945 -0.305054)
			(end 0.12065 -0.305054)
			(stroke
				(width 0.1)
				(type default)
			)
			(layer "B.Fab")
		)
		(fp_line
			(start 0.12065 0.3048)
			(end 0.67945 0.3048)
			(stroke
				(width 0.1)
				(type default)
			)
			(layer "B.Fab")
		)
		(fp_line
			(start 0.12065 0.2794)
			(end 0.12065 0.3048)
			(stroke
				(width 0.1)
				(type default)
			)
			(layer "B.Fab")
		)
		(fp_line
			(start 0.12065 -0.2794)
			(end -0.12065 -0.2794)
			(stroke
				(width 0.1)
				(type default)
			)
			(layer "B.Fab")
		)
		(fp_line
			(start 0.12065 -0.305054)
			(end 0.12065 -0.2794)
			(stroke
				(width 0.1)
				(type default)
			)
			(layer "B.Fab")
		)
		(fp_line
			(start -0.120396 0.3048)
			(end -0.120396 0.2794)
			(stroke
				(width 0.1)
				(type default)
			)
			(layer "B.Fab")
		)
		(fp_line
			(start -0.120396 0.2794)
			(end 0.12065 0.2794)
			(stroke
				(width 0.1)
				(type default)
			)
			(layer "B.Fab")
		)
		(fp_line
			(start -0.12065 -0.2794)
			(end -0.12065 -0.3048)
			(stroke
				(width 0.1)
				(type default)
			)
			(layer "B.Fab")
		)
		(fp_line
			(start -0.12065 -0.3048)
			(end -0.67945 -0.3048)
			(stroke
				(width 0.1)
				(type default)
			)
			(layer "B.Fab")
		)
		(fp_line
			(start -0.67945 0.3048)
			(end -0.120396 0.3048)
			(stroke
				(width 0.1)
				(type default)
			)
			(layer "B.Fab")
		)
		(fp_line
			(start -0.67945 -0.3048)
			(end -0.67945 0.3048)
			(stroke
				(width 0.1)
				(type default)
			)
			(layer "B.Fab")
		)
		(pad "1" smd circle
			(at 0.40005 0)
			(size 0 0)
			(layers "B.Cu" "B.Mask" "B.Paste")
			(net "SVID_PVDDCR_CPU0_P0_SVD_R")
		)
		(pad "2" smd circle
			(at -0.40005 0)
			(size 0 0)
			(layers "B.Cu" "B.Mask" "B.Paste")
			(net "SVID_PVDDCR_CPU0_P0_SVD")
		)
	)
	(footprint ""
		(layer "B.Cu")
		(at 106.085386 -268.418564)
		(property "Reference" "C2383"
			(at 0 0 0)
			(layer "B.SilkS")
			(hide yes)
			(effects
				(font
					(size 1.27 1.27)
				)
				(justify mirror)
			)
		)
		(property "Value" ""
			(at 0 0 0)
			(layer "B.Fab")
			(effects
				(font
					(size 1.27 1.27)
				)
				(justify mirror)
			)
		)
		(duplicate_pad_numbers_are_jumpers no)
		(fp_line
			(start -0.7874 -0.4064)
			(end -0.7874 0.4064)
			(stroke
				(width 0.1524)
				(type default)
			)
			(layer "B.SilkS")
		)
		(fp_line
			(start -0.7874 0.4064)
			(end 0.7874 0.4064)
			(stroke
				(width 0.1524)
				(type default)
			)
			(layer "B.SilkS")
		)
		(fp_line
			(start 0.7874 -0.4064)
			(end -0.7874 -0.4064)
			(stroke
				(width 0.1524)
				(type default)
			)
			(layer "B.SilkS")
		)
		(fp_line
			(start 0.7874 0.4064)
			(end 0.7874 -0.4064)
			(stroke
				(width 0.1524)
				(type default)
			)
			(layer "B.SilkS")
		)
		(fp_line
			(start -0.67945 -0.3048)
			(end -0.67945 0.3048)
			(stroke
				(width 0.1)
				(type default)
			)
			(layer "B.Fab")
		)
		(fp_line
			(start -0.67945 0.3048)
			(end -0.120396 0.3048)
			(stroke
				(width 0.1)
				(type default)
			)
			(layer "B.Fab")
		)
		(fp_line
			(start -0.12065 -0.3048)
			(end -0.67945 -0.3048)
			(stroke
				(width 0.1)
				(type default)
			)
			(layer "B.Fab")
		)
		(fp_line
			(start -0.12065 -0.2794)
			(end -0.12065 -0.3048)
			(stroke
				(width 0.1)
				(type default)
			)
			(layer "B.Fab")
		)
		(fp_line
			(start -0.120396 0.2794)
			(end 0.12065 0.2794)
			(stroke
				(width 0.1)
				(type default)
			)
			(layer "B.Fab")
		)
		(fp_line
			(start -0.120396 0.3048)
			(end -0.120396 0.2794)
			(stroke
				(width 0.1)
				(type default)
			)
			(layer "B.Fab")
		)
		(fp_line
			(start 0.12065 -0.305054)
			(end 0.12065 -0.2794)
			(stroke
				(width 0.1)
				(type default)
			)
			(layer "B.Fab")
		)
		(fp_line
			(start 0.12065 -0.2794)
			(end -0.12065 -0.2794)
			(stroke
				(width 0.1)
				(type default)
			)
			(layer "B.Fab")
		)
		(fp_line
			(start 0.12065 0.2794)
			(end 0.12065 0.3048)
			(stroke
				(width 0.1)
				(type default)
			)
			(layer "B.Fab")
		)
		(fp_line
			(start 0.12065 0.3048)
			(end 0.67945 0.3048)
			(stroke
				(width 0.1)
				(type default)
			)
			(layer "B.Fab")
		)
		(fp_line
			(start 0.67945 -0.305054)
			(end 0.12065 -0.305054)
			(stroke
				(width 0.1)
				(type default)
			)
			(layer "B.Fab")
		)
		(fp_line
			(start 0.67945 0.3048)
			(end 0.67945 -0.305054)
			(stroke
				(width 0.1)
				(type default)
			)
			(layer "B.Fab")
		)
		(pad "1" smd circle
			(at 0.40005 0 180)
			(size 0 0)
			(layers "B.Cu" "B.Mask" "B.Paste")
			(net "PVDDCR_CPU1_P1")
		)
		(pad "2" smd circle
			(at -0.40005 0 180)
			(size 0 0)
			(layers "B.Cu" "B.Mask" "B.Paste")
			(net "GND")
		)
	)
	(footprint ""
		(layer "B.Cu")
		(at 343.960958 -306.828952 180)
		(property "Reference" "R207"
			(at 0 0 0)
			(layer "B.SilkS")
			(hide yes)
			(effects
				(font
					(size 1.27 1.27)
				)
				(justify mirror)
			)
		)
		(property "Value" ""
			(at 0 0 0)
			(layer "B.Fab")
			(effects
				(font
					(size 1.27 1.27)
				)
				(justify mirror)
			)
		)
		(duplicate_pad_numbers_are_jumpers no)
		(fp_line
			(start 0.7874 0.4064)
			(end 0.7874 -0.4064)
			(stroke
				(width 0.1524)
				(type default)
			)
			(layer "B.SilkS")
		)
		(fp_line
			(start 0.7874 -0.4064)
			(end -0.7874 -0.4064)
			(stroke
				(width 0.1524)
				(type default)
			)
			(layer "B.SilkS")
		)
		(fp_line
			(start -0.7874 0.4064)
			(end 0.7874 0.4064)
			(stroke
				(width 0.1524)
				(type default)
			)
			(layer "B.SilkS")
		)
		(fp_line
			(start -0.7874 -0.4064)
			(end -0.7874 0.4064)
			(stroke
				(width 0.1524)
				(type default)
			)
			(layer "B.SilkS")
		)
		(fp_line
			(start 0.67945 0.3048)
			(end 0.67945 -0.305054)
			(stroke
				(width 0.1)
				(type default)
			)
			(layer "B.Fab")
		)
		(fp_line
			(start 0.67945 -0.305054)
			(end 0.12065 -0.305054)
			(stroke
				(width 0.1)
				(type default)
			)
			(layer "B.Fab")
		)
		(fp_line
			(start 0.12065 0.3048)
			(end 0.67945 0.3048)
			(stroke
				(width 0.1)
				(type default)
			)
			(layer "B.Fab")
		)
		(fp_line
			(start 0.12065 0.2794)
			(end 0.12065 0.3048)
			(stroke
				(width 0.1)
				(type default)
			)
			(layer "B.Fab")
		)
		(fp_line
			(start 0.12065 -0.2794)
			(end -0.12065 -0.2794)
			(stroke
				(width 0.1)
				(type default)
			)
			(layer "B.Fab")
		)
		(fp_line
			(start 0.12065 -0.305054)
			(end 0.12065 -0.2794)
			(stroke
				(width 0.1)
				(type default)
			)
			(layer "B.Fab")
		)
		(fp_line
			(start -0.120396 0.3048)
			(end -0.120396 0.2794)
			(stroke
				(width 0.1)
				(type default)
			)
			(layer "B.Fab")
		)
		(fp_line
			(start -0.120396 0.2794)
			(end 0.12065 0.2794)
			(stroke
				(width 0.1)
				(type default)
			)
			(layer "B.Fab")
		)
		(fp_line
			(start -0.12065 -0.2794)
			(end -0.12065 -0.3048)
			(stroke
				(width 0.1)
				(type default)
			)
			(layer "B.Fab")
		)
		(fp_line
			(start -0.12065 -0.3048)
			(end -0.67945 -0.3048)
			(stroke
				(width 0.1)
				(type default)
			)
			(layer "B.Fab")
		)
		(fp_line
			(start -0.67945 0.3048)
			(end -0.120396 0.3048)
			(stroke
				(width 0.1)
				(type default)
			)
			(layer "B.Fab")
		)
		(fp_line
			(start -0.67945 -0.3048)
			(end -0.67945 0.3048)
			(stroke
				(width 0.1)
				(type default)
			)
			(layer "B.Fab")
		)
		(pad "1" smd circle
			(at 0.40005 0)
			(size 0 0)
			(layers "B.Cu" "B.Mask" "B.Paste")
			(net "FM_INT_CPU0_HP_UBM_N")
		)
		(pad "2" smd circle
			(at -0.40005 0)
			(size 0 0)
			(layers "B.Cu" "B.Mask" "B.Paste")
			(net "PVDD18_S5_P0")
		)
	)
	(footprint ""
		(layer "B.Cu")
		(at 75.7936 -383.7432 180)
		(property "Reference" "R756"
			(at 0 0 0)
			(layer "B.SilkS")
			(hide yes)
			(effects
				(font
					(size 1.27 1.27)
				)
				(justify mirror)
			)
		)
		(property "Value" ""
			(at 0 0 0)
			(layer "B.Fab")
			(effects
				(font
					(size 1.27 1.27)
				)
				(justify mirror)
			)
		)
		(duplicate_pad_numbers_are_jumpers no)
		(fp_line
			(start 0.32512 0.175006)
			(end 0.32512 -0.175006)
			(stroke
				(width 0.1)
				(type default)
			)
			(layer "B.Fab")
		)
		(fp_line
			(start 0.32512 -0.175006)
			(end -0.32512 -0.175006)
			(stroke
				(width 0.1)
				(type default)
			)
			(layer "B.Fab")
		)
		(fp_line
			(start -0.32512 0.175006)
			(end 0.32512 0.175006)
			(stroke
				(width 0.1)
				(type default)
			)
			(layer "B.Fab")
		)
		(fp_line
			(start -0.32512 -0.175006)
			(end -0.32512 0.175006)
			(stroke
				(width 0.1)
				(type default)
			)
			(layer "B.Fab")
		)
		(pad "1" smd rect
			(at 0.2667 0)
			(size 0.3048 0.381)
			(layers "B.Cu" "B.Mask" "B.Paste")
			(net "RT_CPU1_P1_SCAN_MODE")
		)
		(pad "2" smd rect
			(at -0.2667 0 180)
			(size 0.3048 0.381)
			(layers "B.Cu" "B.Mask" "B.Paste")
			(net "GND")
		)
	)
	(footprint ""
		(layer "B.Cu")
		(at 216.916 -340.741 -90)
		(property "Reference" "R6752"
			(at 0 0 90)
			(layer "B.SilkS")
			(hide yes)
			(effects
				(font
					(size 1.27 1.27)
				)
				(justify mirror)
			)
		)
		(property "Value" ""
			(at 0 0 90)
			(layer "B.Fab")
			(effects
				(font
					(size 1.27 1.27)
				)
				(justify mirror)
			)
		)
		(duplicate_pad_numbers_are_jumpers no)
		(fp_line
			(start -0.32512 0.175006)
			(end 0.32512 0.175006)
			(stroke
				(width 0.1)
				(type default)
			)
			(layer "B.Fab")
		)
		(fp_line
			(start 0.32512 0.175006)
			(end 0.32512 -0.175006)
			(stroke
				(width 0.1)
				(type default)
			)
			(layer "B.Fab")
		)
		(fp_line
			(start -0.32512 -0.175006)
			(end -0.32512 0.175006)
			(stroke
				(width 0.1)
				(type default)
			)
			(layer "B.Fab")
		)
		(fp_line
			(start 0.32512 -0.175006)
			(end -0.32512 -0.175006)
			(stroke
				(width 0.1)
				(type default)
			)
			(layer "B.Fab")
		)
		(pad "1" smd rect
			(at 0.2667 0 90)
			(size 0.3048 0.381)
			(layers "B.Cu" "B.Mask" "B.Paste")
			(net "P1V8_CPU1_RT_1D")
		)
		(pad "2" smd rect
			(at -0.2667 0 270)
			(size 0.3048 0.381)
			(layers "B.Cu" "B.Mask" "B.Paste")
			(net "SMB_RT_CPU1_P2_R_SDA")
		)
	)
	(footprint ""
		(layer "B.Cu")
		(at 374.440958 -208.530952 -90)
		(property "Reference" "R400"
			(at 0 0 90)
			(layer "B.SilkS")
			(hide yes)
			(effects
				(font
					(size 1.27 1.27)
				)
				(justify mirror)
			)
		)
		(property "Value" ""
			(at 0 0 90)
			(layer "B.Fab")
			(effects
				(font
					(size 1.27 1.27)
				)
				(justify mirror)
			)
		)
		(duplicate_pad_numbers_are_jumpers no)
		(fp_line
			(start -0.7874 0.4064)
			(end 0.7874 0.4064)
			(stroke
				(width 0.1524)
				(type default)
			)
			(layer "B.SilkS")
		)
		(fp_line
			(start 0.7874 0.4064)
			(end 0.7874 -0.4064)
			(stroke
				(width 0.1524)
				(type default)
			)
			(layer "B.SilkS")
		)
		(fp_line
			(start -0.7874 -0.4064)
			(end -0.7874 0.4064)
			(stroke
				(width 0.1524)
				(type default)
			)
			(layer "B.SilkS")
		)
		(fp_line
			(start 0.7874 -0.4064)
			(end -0.7874 -0.4064)
			(stroke
				(width 0.1524)
				(type default)
			)
			(layer "B.SilkS")
		)
		(fp_line
			(start -0.67945 0.3048)
			(end -0.120396 0.3048)
			(stroke
				(width 0.1)
				(type default)
			)
			(layer "B.Fab")
		)
		(fp_line
			(start -0.120396 0.3048)
			(end -0.120396 0.2794)
			(stroke
				(width 0.1)
				(type default)
			)
			(layer "B.Fab")
		)
		(fp_line
			(start 0.12065 0.3048)
			(end 0.67945 0.3048)
			(stroke
				(width 0.1)
				(type default)
			)
			(layer "B.Fab")
		)
		(fp_line
			(start 0.67945 0.3048)
			(end 0.67945 -0.305054)
			(stroke
				(width 0.1)
				(type default)
			)
			(layer "B.Fab")
		)
		(fp_line
			(start -0.120396 0.2794)
			(end 0.12065 0.2794)
			(stroke
				(width 0.1)
				(type default)
			)
			(layer "B.Fab")
		)
		(fp_line
			(start 0.12065 0.2794)
			(end 0.12065 0.3048)
			(stroke
				(width 0.1)
				(type default)
			)
			(layer "B.Fab")
		)
		(fp_line
			(start -0.12065 -0.2794)
			(end -0.12065 -0.3048)
			(stroke
				(width 0.1)
				(type default)
			)
			(layer "B.Fab")
		)
		(fp_line
			(start 0.12065 -0.2794)
			(end -0.12065 -0.2794)
			(stroke
				(width 0.1)
				(type default)
			)
			(layer "B.Fab")
		)
		(fp_line
			(start -0.67945 -0.3048)
			(end -0.67945 0.3048)
			(stroke
				(width 0.1)
				(type default)
			)
			(layer "B.Fab")
		)
		(fp_line
			(start -0.12065 -0.3048)
			(end -0.67945 -0.3048)
			(stroke
				(width 0.1)
				(type default)
			)
			(layer "B.Fab")
		)
		(fp_line
			(start 0.12065 -0.305054)
			(end 0.12065 -0.2794)
			(stroke
				(width 0.1)
				(type default)
			)
			(layer "B.Fab")
		)
		(fp_line
			(start 0.67945 -0.305054)
			(end 0.12065 -0.305054)
			(stroke
				(width 0.1)
				(type default)
			)
			(layer "B.Fab")
		)
		(pad "1" smd circle
			(at 0.40005 0 90)
			(size 0 0)
			(layers "B.Cu" "B.Mask" "B.Paste")
			(net "PVDD18_S5_P0")
		)
		(pad "2" smd circle
			(at -0.40005 0 90)
			(size 0 0)
			(layers "B.Cu" "B.Mask" "B.Paste")
			(net "JTAG_CPU0_TRST_N")
		)
	)
)
